(kicad_pcb
	(version 20260206)
	(generator "pcbnew")
	(generator_version "10.0")
	(general
		(thickness 1.6)
		(legacy_teardrops no)
	)
	(paper "A4")
	(title_block
		(title "Wiwynn_Tioga_Pass_MB.brd")
		(comment 1 "Tioga Pass / footprint 1664 of 4770 (U7C1), pads 1266-1310 of 1310")
	)
	(layers
		(0 "F.Cu" signal "TOP")
		(4 "In1.Cu" signal "L2GND")
		(6 "In2.Cu" signal "L3")
		(8 "In3.Cu" signal "L4GND")
		(10 "In4.Cu" signal "L5")
		(12 "In5.Cu" signal "L6GND")
		(14 "In6.Cu" signal "L7VCC")
		(16 "In7.Cu" signal "L8VCC")
		(18 "In8.Cu" signal "L9GND")
		(20 "In9.Cu" signal "L10")
		(22 "In10.Cu" signal "L11GND")
		(24 "In11.Cu" signal "L12")
		(26 "In12.Cu" signal "L13GND")
		(2 "B.Cu" signal "BOTTOM")
		(9 "F.Adhes" user "F.Adhesive")
		(11 "B.Adhes" user "B.Adhesive")
		(13 "F.Paste" user "Package Geometry/Pastemask Top")
		(15 "B.Paste" user "Package Geometry/Pastemask Bottom")
		(5 "F.SilkS" user "Ref Des/Silkscreen Top")
		(7 "B.SilkS" user "Ref Des/Silkscreen Bottom")
		(1 "F.Mask" user "Board Geometry/Soldermask Top")
		(3 "B.Mask" user "Board Geometry/Soldermask Bottom")
		(17 "Dwgs.User" user "User.Drawings")
		(19 "Cmts.User" user "User.Comments")
		(21 "Eco1.User" user "User.Eco1")
		(23 "Eco2.User" user "User.Eco2")
		(25 "Edge.Cuts" user "Board Geometry/Outline")
		(27 "Margin" user)
		(31 "F.CrtYd" user "Package Geometry/Place Bound Top")
		(29 "B.CrtYd" user "Package Geometry/Place Bound Bottom")
		(35 "F.Fab" user "Ref Des/Assembly Top")
		(33 "B.Fab" user "Ref Des/Assembly Bottom")
	)
	(footprint ""
		(layer "F.Cu")
		(at 387.985 -109.855 90)
		(property "Reference" "U7C1"
			(at 17.75333 -13.335 0)
			(unlocked yes)
			(layer "F.SilkS")
			(effects
				(font
					(size 0.7874 0.5842)
					(thickness 0.1524)
				)
				(justify left)
			)
		)
		(property "Value" ""
			(at 0 0 90)
			(layer "F.Fab")
			(effects
				(font
					(size 1.27 1.27)
				)
			)
		)
		(duplicate_pad_numbers_are_jumpers no)
		(pad "V72" smd oval
			(at 16.310102 -5.999988 180)
			(size 0.254 0.3302)
			(layers "F.Cu" "F.Mask" "F.Paste")
			(net "SATA6G_PCH_PCIE_UP_SATA_TXP<1>")
		)
		(pad "W2" smd circle
			(at -15.895066 -5.500116 180)
			(size 0.3048 0.3048)
			(layers "F.Cu" "F.Mask" "F.Paste")
			(net "LPC_LAD2_IO2")
		)
		(pad "W4" smd circle
			(at -15.064994 -5.500116 180)
			(size 0.3048 0.3048)
			(layers "F.Cu" "F.Mask" "F.Paste")
			(net "Net_16")
		)
		(pad "W9" smd circle
			(at -12.8778 -5.20065)
			(size 0.381 0.381)
			(layers "F.Cu" "F.Mask" "F.Paste")
			(net "GND")
		)
		(pad "W13" smd circle
			(at -11.16076 -5.20065)
			(size 0.381 0.381)
			(layers "F.Cu" "F.Mask" "F.Paste")
			(net "GND")
		)
		(pad "W17" smd circle
			(at -9.44372 -5.20065)
			(size 0.381 0.381)
			(layers "F.Cu" "F.Mask" "F.Paste")
			(net "GND")
		)
		(pad "W20" smd circle
			(at -7.72668 -5.20065)
			(size 0.381 0.381)
			(layers "F.Cu" "F.Mask" "F.Paste")
			(net "GND")
		)
		(pad "W24" smd circle
			(at -6.00964 -5.20065)
			(size 0.381 0.381)
			(layers "F.Cu" "F.Mask" "F.Paste")
			(net "GND")
		)
		(pad "W50" smd circle
			(at 6.00964 -5.20065)
			(size 0.381 0.381)
			(layers "F.Cu" "F.Mask" "F.Paste")
			(net "P1V05_PCH_STBY_ISCLK_PLL")
		)
		(pad "W54" smd circle
			(at 7.72668 -5.20065)
			(size 0.381 0.381)
			(layers "F.Cu" "F.Mask" "F.Paste")
			(net "TP_PCH_RSVD35")
		)
		(pad "W58" smd circle
			(at 9.44372 -5.20065)
			(size 0.381 0.381)
			(layers "F.Cu" "F.Mask" "F.Paste")
			(net "GND")
		)
		(pad "W61" smd circle
			(at 11.16076 -5.20065)
			(size 0.381 0.381)
			(layers "F.Cu" "F.Mask" "F.Paste")
			(net "GND")
		)
		(pad "W65" smd circle
			(at 12.8778 -5.20065)
			(size 0.381 0.381)
			(layers "F.Cu" "F.Mask" "F.Paste")
			(net "P3E_CPU0_PE1_PCH_R_RXN<14>")
		)
		(pad "W69" smd circle
			(at 15.064994 -5.500116)
			(size 0.3048 0.3048)
			(layers "F.Cu" "F.Mask" "F.Paste")
			(net "SATA6G_PCH_PCIE_UP_SATA_TXN<0>")
		)
		(pad "W71" smd circle
			(at 15.895066 -5.500116)
			(size 0.3048 0.3048)
			(layers "F.Cu" "F.Mask" "F.Paste")
			(net "SATA6G_PCH_PCIE_UP_SATA_TXP<0>")
		)
		(pad "Y1" smd oval
			(at -16.310102 -4.99999 180)
			(size 0.254 0.3302)
			(layers "F.Cu" "F.Mask" "F.Paste")
			(net "LPC_LAD3_IO3")
		)
		(pad "Y3" smd circle
			(at -15.48003 -4.99999 180)
			(size 0.3048 0.3048)
			(layers "F.Cu" "F.Mask" "F.Paste")
			(net "LPC_LAD0_IO0")
		)
		(pad "Y5" smd circle
			(at -14.649958 -4.99999 180)
			(size 0.3048 0.3048)
			(layers "F.Cu" "F.Mask" "F.Paste")
			(net "GND")
		)
		(pad "Y7" smd circle
			(at -13.73632 -4.70535)
			(size 0.381 0.381)
			(layers "F.Cu" "F.Mask" "F.Paste")
			(net "FM_CPU0_PROCHOT_PCH_N")
		)
		(pad "Y11" smd circle
			(at -12.01928 -4.70535)
			(size 0.381 0.381)
			(layers "F.Cu" "F.Mask" "F.Paste")
			(net "H_CPU1_MEMKLM_MEMHOT_PCH_N")
		)
		(pad "Y15" smd circle
			(at -10.30224 -4.70535)
			(size 0.381 0.381)
			(layers "F.Cu" "F.Mask" "F.Paste")
			(net "H_CPU0_MEMABC_MEMHOT_PCH_N")
		)
		(pad "Y18" smd circle
			(at -8.5852 -4.70535)
			(size 0.381 0.381)
			(layers "F.Cu" "F.Mask" "F.Paste")
			(net "FM_PRSNT_2_4_N")
		)
		(pad "Y22" smd circle
			(at -6.86816 -4.70535)
			(size 0.381 0.381)
			(layers "F.Cu" "F.Mask" "F.Paste")
			(net "GND")
		)
		(pad "Y26" smd circle
			(at -5.20065 -5.04825 180)
			(size 0.381 0.381)
			(layers "F.Cu" "F.Mask" "F.Paste")
			(net "P1V05_PCH_STBY")
		)
		(pad "Y27" smd circle
			(at -4.40055 -5.04825 180)
			(size 0.381 0.381)
			(layers "F.Cu" "F.Mask" "F.Paste")
			(net "GND")
		)
		(pad "Y29" smd circle
			(at -3.60045 -5.04825 180)
			(size 0.381 0.381)
			(layers "F.Cu" "F.Mask" "F.Paste")
			(net "PVNN_PCH_STBY")
		)
		(pad "Y30" smd circle
			(at -2.80035 -5.04825 180)
			(size 0.381 0.381)
			(layers "F.Cu" "F.Mask" "F.Paste")
			(net "PVNN_PCH_STBY")
		)
		(pad "Y32" smd circle
			(at -2.00025 -5.04825 180)
			(size 0.381 0.381)
			(layers "F.Cu" "F.Mask" "F.Paste")
			(net "PVNN_PCH_STBY")
		)
		(pad "Y34" smd circle
			(at -1.20015 -5.04825 180)
			(size 0.381 0.381)
			(layers "F.Cu" "F.Mask" "F.Paste")
			(net "PVNN_PCH_STBY")
		)
		(pad "Y36" smd circle
			(at -0.40005 -5.04825 180)
			(size 0.381 0.381)
			(layers "F.Cu" "F.Mask" "F.Paste")
			(net "PVNN_PCH_STBY")
		)
		(pad "Y37" smd circle
			(at 0.40005 -5.04825 180)
			(size 0.381 0.381)
			(layers "F.Cu" "F.Mask" "F.Paste")
			(net "PVNN_PCH_STBY")
		)
		(pad "Y39" smd circle
			(at 1.20015 -5.04825 180)
			(size 0.381 0.381)
			(layers "F.Cu" "F.Mask" "F.Paste")
			(net "PVNN_PCH_STBY")
		)
		(pad "Y41" smd circle
			(at 2.00025 -5.04825 180)
			(size 0.381 0.381)
			(layers "F.Cu" "F.Mask" "F.Paste")
			(net "PVNN_PCH_STBY")
		)
		(pad "Y43" smd circle
			(at 2.80035 -5.04825 180)
			(size 0.381 0.381)
			(layers "F.Cu" "F.Mask" "F.Paste")
			(net "GND")
		)
		(pad "Y45" smd circle
			(at 3.60045 -5.04825 180)
			(size 0.381 0.381)
			(layers "F.Cu" "F.Mask" "F.Paste")
			(net "P1V05_PCH_STBY")
		)
		(pad "Y46" smd circle
			(at 4.40055 -5.04825 180)
			(size 0.381 0.381)
			(layers "F.Cu" "F.Mask" "F.Paste")
			(net "P1V05_PCH_STBY")
		)
		(pad "Y48" smd circle
			(at 5.20065 -5.04825 180)
			(size 0.381 0.381)
			(layers "F.Cu" "F.Mask" "F.Paste")
			(net "GND")
		)
		(pad "Y52" smd circle
			(at 6.86816 -4.70535)
			(size 0.381 0.381)
			(layers "F.Cu" "F.Mask" "F.Paste")
			(net "GND")
		)
		(pad "Y56" smd circle
			(at 8.5852 -4.70535)
			(size 0.381 0.381)
			(layers "F.Cu" "F.Mask" "F.Paste")
			(net "TP_PCH_RSVD34")
		)
		(pad "Y59" smd circle
			(at 10.30224 -4.70535)
			(size 0.381 0.381)
			(layers "F.Cu" "F.Mask" "F.Paste")
			(net "GND")
		)
		(pad "Y63" smd circle
			(at 12.01928 -4.70535)
			(size 0.381 0.381)
			(layers "F.Cu" "F.Mask" "F.Paste")
			(net "GND")
		)
		(pad "Y66" smd circle
			(at 13.73632 -4.70535)
			(size 0.381 0.381)
			(layers "F.Cu" "F.Mask" "F.Paste")
			(net "P3E_CPU0_PE1_PCH_R_RXN<15>")
		)
		(pad "Y68" smd circle
			(at 14.649958 -4.99999)
			(size 0.3048 0.3048)
			(layers "F.Cu" "F.Mask" "F.Paste")
			(net "GND")
		)
		(pad "Y70" smd circle
			(at 15.48003 -4.99999)
			(size 0.3048 0.3048)
			(layers "F.Cu" "F.Mask" "F.Paste")
			(net "GND")
		)
		(pad "Y72" smd oval
			(at 16.310102 -4.99999 180)
			(size 0.254 0.3302)
			(layers "F.Cu" "F.Mask" "F.Paste")
			(net "GND")
		)
	)
)
